# T6G (Grand Teton) — schematic netlist excerpt (pin names and nets, part order shuffled) for the footprints in the layout excerpt that follows; sources: Cadence DE-HDL packaged netlist, KiCad conversion of 04192023_DAF0TMB3IC0_F0TG_MB_C_brd_V02_OCP.brd

R1578  Q_RES  49.9 1% CHIP  pkg 0402LF  page 96 : A = I3C_SPD_DDRGL_CPU0_SCL ; B = I3C_SPD_DDRK_CPU0_SCL
C258  Q_CAP  4.7UF 6.3V 20% X6S  pkg 0402  page 323 : A = P0V9_CPU1_RT0_2A ; B = GND

(kicad_pcb
	(version 20260206)
	(generator "pcbnew")
	(generator_version "10.0")
	(general
		(thickness 1.6)
		(legacy_teardrops no)
	)
	(paper "A4")
	(title_block
		(title "04192023_DAF0TMB3IC0_F0TG_MB_C_brd_V02_OCP.brd")
		(comment 1 "Grand Teton / footprints 5125-5126 of 8354")
	)
	(layers
		(0 "F.Cu" signal "TOP")
		(4 "In1.Cu" signal "GND")
		(6 "In2.Cu" signal "IN1")
		(8 "In3.Cu" signal "GND1")
		(10 "In4.Cu" signal "IN2")
		(12 "In5.Cu" signal "GND2")
		(14 "In6.Cu" signal "IN3")
		(16 "In7.Cu" signal "GND3")
		(18 "In8.Cu" signal "VCC")
		(20 "In9.Cu" signal "VCC1")
		(22 "In10.Cu" signal "GND4")
		(24 "In11.Cu" signal "IN4")
		(26 "In12.Cu" signal "GND5")
		(28 "In13.Cu" signal "IN5")
		(30 "In14.Cu" signal "GND6")
		(32 "In15.Cu" signal "IN6")
		(34 "In16.Cu" signal "GND7")
		(2 "B.Cu" signal "BOTTOM")
		(9 "F.Adhes" user "F.Adhesive")
		(11 "B.Adhes" user "B.Adhesive")
		(13 "F.Paste" user "Package Geometry/Pastemask Top")
		(15 "B.Paste" user "Package Geometry/Pastemask Bottom")
		(5 "F.SilkS" user "Ref Des/Silkscreen Top")
		(7 "B.SilkS" user "Ref Des/Silkscreen Bottom")
		(1 "F.Mask" user "Board Geometry/Soldermask Top")
		(3 "B.Mask" user "Board Geometry/Soldermask Bottom")
		(17 "Dwgs.User" user "User.Drawings")
		(19 "Cmts.User" user "User.Comments")
		(21 "Eco1.User" user "User.Eco1")
		(23 "Eco2.User" user "User.Eco2")
		(25 "Edge.Cuts" user "Board Geometry/Outline")
		(27 "Margin" user)
		(31 "F.CrtYd" user "Package Geometry/Place Bound Top")
		(29 "B.CrtYd" user "Package Geometry/Place Bound Bottom")
		(35 "F.Fab" user "Ref Des/Assembly Top")
		(33 "B.Fab" user "Ref Des/Assembly Bottom")
	)
	(footprint ""
		(layer "B.Cu")
		(at 64.191388 -390.560052 90)
		(property "Reference" "C258"
			(at 0 0 90)
			(layer "B.SilkS")
			(hide yes)
			(effects
				(font
					(size 1.27 1.27)
				)
				(justify mirror)
			)
		)
		(property "Value" ""
			(at 0 0 90)
			(layer "B.Fab")
			(effects
				(font
					(size 1.27 1.27)
				)
				(justify mirror)
			)
		)
		(duplicate_pad_numbers_are_jumpers no)
		(fp_line
			(start 0.7874 -0.4064)
			(end -0.7874 -0.4064)
			(stroke
				(width 0.1524)
				(type default)
			)
			(layer "B.SilkS")
		)
		(fp_line
			(start -0.7874 -0.4064)
			(end -0.7874 0.4064)
			(stroke
				(width 0.1524)
				(type default)
			)
			(layer "B.SilkS")
		)
		(fp_line
			(start 0.7874 0.4064)
			(end 0.7874 -0.4064)
			(stroke
				(width 0.1524)
				(type default)
			)
			(layer "B.SilkS")
		)
		(fp_line
			(start -0.7874 0.4064)
			(end 0.7874 0.4064)
			(stroke
				(width 0.1524)
				(type default)
			)
			(layer "B.SilkS")
		)
		(fp_line
			(start 0.67945 -0.305054)
			(end 0.12065 -0.305054)
			(stroke
				(width 0.1)
				(type default)
			)
			(layer "B.Fab")
		)
		(fp_line
			(start 0.12065 -0.305054)
			(end 0.12065 -0.2794)
			(stroke
				(width 0.1)
				(type default)
			)
			(layer "B.Fab")
		)
		(fp_line
			(start -0.12065 -0.3048)
			(end -0.67945 -0.3048)
			(stroke
				(width 0.1)
				(type default)
			)
			(layer "B.Fab")
		)
		(fp_line
			(start -0.67945 -0.3048)
			(end -0.67945 0.3048)
			(stroke
				(width 0.1)
				(type default)
			)
			(layer "B.Fab")
		)
		(fp_line
			(start 0.12065 -0.2794)
			(end -0.12065 -0.2794)
			(stroke
				(width 0.1)
				(type default)
			)
			(layer "B.Fab")
		)
		(fp_line
			(start -0.12065 -0.2794)
			(end -0.12065 -0.3048)
			(stroke
				(width 0.1)
				(type default)
			)
			(layer "B.Fab")
		)
		(fp_line
			(start 0.12065 0.2794)
			(end 0.12065 0.3048)
			(stroke
				(width 0.1)
				(type default)
			)
			(layer "B.Fab")
		)
		(fp_line
			(start -0.120396 0.2794)
			(end 0.12065 0.2794)
			(stroke
				(width 0.1)
				(type default)
			)
			(layer "B.Fab")
		)
		(fp_line
			(start 0.67945 0.3048)
			(end 0.67945 -0.305054)
			(stroke
				(width 0.1)
				(type default)
			)
			(layer "B.Fab")
		)
		(fp_line
			(start 0.12065 0.3048)
			(end 0.67945 0.3048)
			(stroke
				(width 0.1)
				(type default)
			)
			(layer "B.Fab")
		)
		(fp_line
			(start -0.120396 0.3048)
			(end -0.120396 0.2794)
			(stroke
				(width 0.1)
				(type default)
			)
			(layer "B.Fab")
		)
		(fp_line
			(start -0.67945 0.3048)
			(end -0.120396 0.3048)
			(stroke
				(width 0.1)
				(type default)
			)
			(layer "B.Fab")
		)
		(pad "1" smd circle
			(at 0.40005 0 270)
			(size 0 0)
			(layers "B.Cu" "B.Mask" "B.Paste")
			(net "P0V9_CPU1_RT0_2A")
		)
		(pad "2" smd circle
			(at -0.40005 0 270)
			(size 0 0)
			(layers "B.Cu" "B.Mask" "B.Paste")
			(net "GND")
		)
	)
	(footprint ""
		(layer "B.Cu")
		(at 445.888364 -194.89547 180)
		(property "Reference" "R1578"
			(at 0 0 0)
			(layer "B.SilkS")
			(hide yes)
			(effects
				(font
					(size 1.27 1.27)
				)
				(justify mirror)
			)
		)
		(property "Value" ""
			(at 0 0 0)
			(layer "B.Fab")
			(effects
				(font
					(size 1.27 1.27)
				)
				(justify mirror)
			)
		)
		(duplicate_pad_numbers_are_jumpers no)
		(fp_line
			(start 0.7874 0.4064)
			(end 0.7874 -0.4064)
			(stroke
				(width 0.1524)
				(type default)
			)
			(layer "B.SilkS")
		)
		(fp_line
			(start 0.7874 -0.4064)
			(end -0.7874 -0.4064)
			(stroke
				(width 0.1524)
				(type default)
			)
			(layer "B.SilkS")
		)
		(fp_line
			(start -0.7874 0.4064)
			(end 0.7874 0.4064)
			(stroke
				(width 0.1524)
				(type default)
			)
			(layer "B.SilkS")
		)
		(fp_line
			(start -0.7874 -0.4064)
			(end -0.7874 0.4064)
			(stroke
				(width 0.1524)
				(type default)
			)
			(layer "B.SilkS")
		)
		(fp_line
			(start 0.67945 0.3048)
			(end 0.67945 -0.305054)
			(stroke
				(width 0.1)
				(type default)
			)
			(layer "B.Fab")
		)
		(fp_line
			(start 0.67945 -0.305054)
			(end 0.12065 -0.305054)
			(stroke
				(width 0.1)
				(type default)
			)
			(layer "B.Fab")
		)
		(fp_line
			(start 0.12065 0.3048)
			(end 0.67945 0.3048)
			(stroke
				(width 0.1)
				(type default)
			)
			(layer "B.Fab")
		)
		(fp_line
			(start 0.12065 0.2794)
			(end 0.12065 0.3048)
			(stroke
				(width 0.1)
				(type default)
			)
			(layer "B.Fab")
		)
		(fp_line
			(start 0.12065 -0.2794)
			(end -0.12065 -0.2794)
			(stroke
				(width 0.1)
				(type default)
			)
			(layer "B.Fab")
		)
		(fp_line
			(start 0.12065 -0.305054)
			(end 0.12065 -0.2794)
			(stroke
				(width 0.1)
				(type default)
			)
			(layer "B.Fab")
		)
		(fp_line
			(start -0.120396 0.3048)
			(end -0.120396 0.2794)
			(stroke
				(width 0.1)
				(type default)
			)
			(layer "B.Fab")
		)
		(fp_line
			(start -0.120396 0.2794)
			(end 0.12065 0.2794)
			(stroke
				(width 0.1)
				(type default)
			)
			(layer "B.Fab")
		)
		(fp_line
			(start -0.12065 -0.2794)
			(end -0.12065 -0.3048)
			(stroke
				(width 0.1)
				(type default)
			)
			(layer "B.Fab")
		)
		(fp_line
			(start -0.12065 -0.3048)
			(end -0.67945 -0.3048)
			(stroke
				(width 0.1)
				(type default)
			)
			(layer "B.Fab")
		)
		(fp_line
			(start -0.67945 0.3048)
			(end -0.120396 0.3048)
			(stroke
				(width 0.1)
				(type default)
			)
			(layer "B.Fab")
		)
		(fp_line
			(start -0.67945 -0.3048)
			(end -0.67945 0.3048)
			(stroke
				(width 0.1)
				(type default)
			)
			(layer "B.Fab")
		)
		(pad "1" smd circle
			(at 0.40005 0)
			(size 0 0)
			(layers "B.Cu" "B.Mask" "B.Paste")
			(net "I3C_SPD_DDRGL_CPU0_SCL")
		)
		(pad "2" smd circle
			(at -0.40005 0)
			(size 0 0)
			(layers "B.Cu" "B.Mask" "B.Paste")
			(net "I3C_SPD_DDRK_CPU0_SCL")
		)
	)
)
